(kicad_pcb
	(version 20260206)
	(generator "pcbnew")
	(generator_version "10.0")
	(general
		(thickness 1.6)
		(legacy_teardrops no)
	)
	(paper "A4")
	(title_block
		(title "Bryce Canyon_SCC_16316-1_OCP.brd")
		(comment 1 "Bryce Canyon / footprints 1197-1204 of 1561")
	)
	(layers
		(0 "F.Cu" signal "TOP")
		(4 "In1.Cu" signal "L2GND")
		(6 "In2.Cu" signal "L3")
		(8 "In3.Cu" signal "L4VCC")
		(10 "In4.Cu" signal "L5VCC")
		(12 "In5.Cu" signal "L6")
		(14 "In6.Cu" signal "L7GND")
		(2 "B.Cu" signal "BOTTOM")
		(9 "F.Adhes" user "F.Adhesive")
		(11 "B.Adhes" user "B.Adhesive")
		(13 "F.Paste" user "Package Geometry/Pastemask Top")
		(15 "B.Paste" user "Package Geometry/Pastemask Bottom")
		(5 "F.SilkS" user "Ref Des/Silkscreen Top")
		(7 "B.SilkS" user "Ref Des/Silkscreen Bottom")
		(1 "F.Mask" user "Board Geometry/Soldermask Top")
		(3 "B.Mask" user "Board Geometry/Soldermask Bottom")
		(17 "Dwgs.User" user "User.Drawings")
		(19 "Cmts.User" user "User.Comments")
		(21 "Eco1.User" user "User.Eco1")
		(23 "Eco2.User" user "User.Eco2")
		(25 "Edge.Cuts" user "Board Geometry/Outline")
		(27 "Margin" user)
		(31 "F.CrtYd" user "Package Geometry/Place Bound Top")
		(29 "B.CrtYd" user "Package Geometry/Place Bound Bottom")
		(35 "F.Fab" user "Ref Des/Assembly Top")
		(33 "B.Fab" user "Ref Des/Assembly Bottom")
	)
	(footprint ""
		(layer "B.Cu")
		(at 177.811176 -39.711122 90)
		(property "Reference" "C421"
			(at 0 0 90)
			(layer "B.SilkS")
			(hide yes)
			(effects
				(font
					(size 1.27 1.27)
				)
				(justify mirror)
			)
		)
		(property "Value" "SCD1U6D3V1KX-GP"
			(at 2.8321 -1.7399 90)
			(unlocked yes)
			(layer "B.Fab")
			(hide yes)
			(effects
				(font
					(size 1.016 1.016)
					(thickness 0.1524)
				)
				(justify mirror)
			)
		)
		(property "Device Type" "C0201H13"
			(at 2.8321 -3.2639 90)
			(unlocked yes)
			(layer "B.Fab")
			(hide yes)
			(effects
				(font
					(size 1.016 1.016)
					(thickness 0.1524)
				)
				(justify mirror)
			)
		)
		(duplicate_pad_numbers_are_jumpers no)
		(fp_rect
			(start 0.2794 0.6477)
			(end -0.2794 -0.6477)
			(stroke
				(width 0)
				(type default)
			)
			(fill no)
			(layer "B.CrtYd")
		)
		(fp_rect
			(start 0.2794 0.6477)
			(end -0.2794 -0.6477)
			(stroke
				(width 0)
				(type default)
			)
			(fill no)
			(layer "B.Fab")
		)
		(pad "1" smd custom
			(at 0 -0.2794 270)
			(size 0.0762 0.0762)
			(layers "B.Cu" "B.Mask" "B.Paste")
			(net "P0V975")
			(options
				(clearance outline)
				(anchor circle)
			)
			(primitives
				(gr_poly
					(pts
						(arc
							(start 0.1524 0.127)
							(mid 0.137521 0.162921)
							(end 0.1016 0.1778)
						)
						(arc
							(start -0.1016 0.1778)
							(mid -0.137521 0.162921)
							(end -0.1524 0.127)
						)
						(arc
							(start -0.1524 -0.127)
							(mid -0.137521 -0.162921)
							(end -0.1016 -0.1778)
						)
						(arc
							(start 0.1016 -0.1778)
							(mid 0.137521 -0.162921)
							(end 0.1524 -0.127)
						)
					)
					(width 0)
					(fill yes)
				)
			)
		)
		(pad "2" smd custom
			(at 0 0.2794 270)
			(size 0.0762 0.0762)
			(layers "B.Cu" "B.Mask" "B.Paste")
			(net "GND")
			(options
				(clearance outline)
				(anchor circle)
			)
			(primitives
				(gr_poly
					(pts
						(arc
							(start 0.1524 0.127)
							(mid 0.137521 0.162921)
							(end 0.1016 0.1778)
						)
						(arc
							(start -0.1016 0.1778)
							(mid -0.137521 0.162921)
							(end -0.1524 0.127)
						)
						(arc
							(start -0.1524 -0.127)
							(mid -0.137521 -0.162921)
							(end -0.1016 -0.1778)
						)
						(arc
							(start 0.1016 -0.1778)
							(mid 0.137521 -0.162921)
							(end 0.1524 -0.127)
						)
					)
					(width 0)
					(fill yes)
				)
			)
		)
	)
	(footprint ""
		(layer "B.Cu")
		(at 177.813208 -37.04971 90)
		(property "Reference" "C433"
			(at 0 0 90)
			(layer "B.SilkS")
			(hide yes)
			(effects
				(font
					(size 1.27 1.27)
				)
				(justify mirror)
			)
		)
		(property "Value" "SCD1U6D3V1KX-GP"
			(at 2.8321 -1.7399 90)
			(unlocked yes)
			(layer "B.Fab")
			(hide yes)
			(effects
				(font
					(size 1.016 1.016)
					(thickness 0.1524)
				)
				(justify mirror)
			)
		)
		(property "Device Type" "C0201H13"
			(at 2.8321 -3.2639 90)
			(unlocked yes)
			(layer "B.Fab")
			(hide yes)
			(effects
				(font
					(size 1.016 1.016)
					(thickness 0.1524)
				)
				(justify mirror)
			)
		)
		(duplicate_pad_numbers_are_jumpers no)
		(fp_rect
			(start 0.2794 0.6477)
			(end -0.2794 -0.6477)
			(stroke
				(width 0)
				(type default)
			)
			(fill no)
			(layer "B.CrtYd")
		)
		(fp_rect
			(start 0.2794 0.6477)
			(end -0.2794 -0.6477)
			(stroke
				(width 0)
				(type default)
			)
			(fill no)
			(layer "B.Fab")
		)
		(pad "1" smd custom
			(at 0 -0.2794 270)
			(size 0.0762 0.0762)
			(layers "B.Cu" "B.Mask" "B.Paste")
			(net "P0V975")
			(options
				(clearance outline)
				(anchor circle)
			)
			(primitives
				(gr_poly
					(pts
						(arc
							(start 0.1524 0.127)
							(mid 0.137521 0.162921)
							(end 0.1016 0.1778)
						)
						(arc
							(start -0.1016 0.1778)
							(mid -0.137521 0.162921)
							(end -0.1524 0.127)
						)
						(arc
							(start -0.1524 -0.127)
							(mid -0.137521 -0.162921)
							(end -0.1016 -0.1778)
						)
						(arc
							(start 0.1016 -0.1778)
							(mid 0.137521 -0.162921)
							(end 0.1524 -0.127)
						)
					)
					(width 0)
					(fill yes)
				)
			)
		)
		(pad "2" smd custom
			(at 0 0.2794 270)
			(size 0.0762 0.0762)
			(layers "B.Cu" "B.Mask" "B.Paste")
			(net "GND")
			(options
				(clearance outline)
				(anchor circle)
			)
			(primitives
				(gr_poly
					(pts
						(arc
							(start 0.1524 0.127)
							(mid 0.137521 0.162921)
							(end 0.1016 0.1778)
						)
						(arc
							(start -0.1016 0.1778)
							(mid -0.137521 0.162921)
							(end -0.1524 0.127)
						)
						(arc
							(start -0.1524 -0.127)
							(mid -0.137521 -0.162921)
							(end -0.1016 -0.1778)
						)
						(arc
							(start 0.1016 -0.1778)
							(mid 0.137521 -0.162921)
							(end 0.1524 -0.127)
						)
					)
					(width 0)
					(fill yes)
				)
			)
		)
	)
	(footprint ""
		(layer "B.Cu")
		(at 197.104 -20.828)
		(property "Reference" "Q5"
			(at 0 0 0)
			(layer "B.SilkS")
			(hide yes)
			(effects
				(font
					(size 1.27 1.27)
				)
				(justify mirror)
			)
		)
		(property "Value" "2N7002K-1-GP"
			(at -0.127 -8.9662 0)
			(unlocked yes)
			(layer "B.Fab")
			(hide yes)
			(effects
				(font
					(size 1.016 1.016)
					(thickness 0.1524)
				)
				(justify mirror)
			)
		)
		(property "Device Type" "SOT23DGS2D4H44"
			(at -0.127 -10.4902 0)
			(unlocked yes)
			(layer "B.Fab")
			(hide yes)
			(effects
				(font
					(size 1.016 1.016)
					(thickness 0.1524)
				)
				(justify mirror)
			)
		)
		(duplicate_pad_numbers_are_jumpers no)
		(fp_line
			(start -1.651 -1.778)
			(end 1.651 -1.778)
			(stroke
				(width 0.1524)
				(type default)
			)
			(layer "B.SilkS")
		)
		(fp_line
			(start -1.651 1.778)
			(end -1.651 -1.778)
			(stroke
				(width 0.1524)
				(type default)
			)
			(layer "B.SilkS")
		)
		(fp_line
			(start 1.651 -1.778)
			(end 1.651 1.778)
			(stroke
				(width 0.1524)
				(type default)
			)
			(layer "B.SilkS")
		)
		(fp_line
			(start 1.651 1.778)
			(end -1.651 1.778)
			(stroke
				(width 0.1524)
				(type default)
			)
			(layer "B.SilkS")
		)
		(fp_poly
			(pts
				(xy 1.778 1.8796) (xy 1.778 -1.8796) (xy -1.778 -1.8796) (xy -1.778 1.8796)
			)
			(stroke
				(width 0)
				(type default)
			)
			(fill no)
			(layer "B.CrtYd")
		)
		(fp_poly
			(pts
				(xy 1.778 1.8796) (xy 1.778 -1.8796) (xy -1.778 -1.8796) (xy -1.778 1.8796)
			)
			(stroke
				(width 0)
				(type default)
			)
			(fill no)
			(layer "B.Fab")
		)
		(pad "D" smd custom
			(at 0 -0.9525 180)
			(size 0.1905 0.1905)
			(layers "B.Cu" "B.Mask" "B.Paste")
			(net "SYS_RST")
			(options
				(clearance outline)
				(anchor circle)
			)
			(primitives
				(gr_poly
					(pts
						(arc
							(start -0.1778 -0.5715)
							(mid -0.321484 -0.511984)
							(end -0.381 -0.3683)
						)
						(arc
							(start -0.381 0.3683)
							(mid -0.321484 0.511984)
							(end -0.1778 0.5715)
						)
						(arc
							(start 0.1778 0.5715)
							(mid 0.321484 0.511984)
							(end 0.381 0.3683)
						)
						(arc
							(start 0.381 -0.3683)
							(mid 0.321484 -0.511984)
							(end 0.1778 -0.5715)
						)
					)
					(width 0)
					(fill yes)
				)
			)
		)
		(pad "G" smd custom
			(at 0.98425 0.9525 180)
			(size 0.1905 0.1905)
			(layers "B.Cu" "B.Mask" "B.Paste")
			(net "P3V3_STBY_R")
			(options
				(clearance outline)
				(anchor circle)
			)
			(primitives
				(gr_poly
					(pts
						(arc
							(start -0.1778 -0.5715)
							(mid -0.321484 -0.511984)
							(end -0.381 -0.3683)
						)
						(arc
							(start -0.381 0.3683)
							(mid -0.321484 0.511984)
							(end -0.1778 0.5715)
						)
						(arc
							(start 0.1778 0.5715)
							(mid 0.321484 0.511984)
							(end 0.381 0.3683)
						)
						(arc
							(start 0.381 -0.3683)
							(mid 0.321484 -0.511984)
							(end 0.1778 -0.5715)
						)
					)
					(width 0)
					(fill yes)
				)
			)
		)
		(pad "S" smd custom
			(at -0.98425 0.9525 180)
			(size 0.1905 0.1905)
			(layers "B.Cu" "B.Mask" "B.Paste")
			(net "GND")
			(options
				(clearance outline)
				(anchor circle)
			)
			(primitives
				(gr_poly
					(pts
						(arc
							(start -0.1778 -0.5715)
							(mid -0.321484 -0.511984)
							(end -0.381 -0.3683)
						)
						(arc
							(start -0.381 0.3683)
							(mid -0.321484 0.511984)
							(end -0.1778 0.5715)
						)
						(arc
							(start 0.1778 0.5715)
							(mid 0.321484 0.511984)
							(end 0.381 0.3683)
						)
						(arc
							(start 0.381 -0.3683)
							(mid 0.321484 -0.511984)
							(end 0.1778 -0.5715)
						)
					)
					(width 0)
					(fill yes)
				)
			)
		)
	)
	(footprint ""
		(layer "B.Cu")
		(at 119.25046 -74.618088 180)
		(property "Reference" "C121"
			(at 0 0 0)
			(layer "B.SilkS")
			(hide yes)
			(effects
				(font
					(size 1.27 1.27)
				)
				(justify mirror)
			)
		)
		(property "Value" "SC10U6D3V2MX-GP-U"
			(at 1.524 -1.905 180)
			(unlocked yes)
			(layer "B.Fab")
			(hide yes)
			(effects
				(font
					(size 1.016 1.016)
					(thickness 0.1524)
				)
				(justify mirror)
			)
		)
		(property "Device Type" "C402-TO0D2H28"
			(at 1.524 -3.429 180)
			(unlocked yes)
			(layer "B.Fab")
			(hide yes)
			(effects
				(font
					(size 1.016 1.016)
					(thickness 0.1524)
				)
				(justify mirror)
			)
		)
		(duplicate_pad_numbers_are_jumpers no)
		(fp_rect
			(start 0.4826 0.889)
			(end -0.4826 -0.889)
			(stroke
				(width 0)
				(type default)
			)
			(fill no)
			(layer "B.CrtYd")
		)
		(fp_rect
			(start 0.4826 0.889)
			(end -0.4826 -0.889)
			(stroke
				(width 0)
				(type default)
			)
			(fill no)
			(layer "B.Fab")
		)
		(pad "1" smd custom
			(at 0 -0.4572)
			(size 0.1524 0.1524)
			(layers "B.Cu" "B.Mask" "B.Paste")
			(net "P1V8_E")
			(options
				(clearance outline)
				(anchor circle)
			)
			(primitives
				(gr_poly
					(pts
						(arc
							(start -0.254 -0.3048)
							(mid -0.325842 -0.275042)
							(end -0.3556 -0.2032)
						)
						(arc
							(start -0.3556 0.2032)
							(mid -0.325842 0.275042)
							(end -0.254 0.3048)
						)
						(arc
							(start 0.254 0.3048)
							(mid 0.325842 0.275042)
							(end 0.3556 0.2032)
						)
						(arc
							(start 0.3556 -0.2032)
							(mid 0.325842 -0.275042)
							(end 0.254 -0.3048)
						)
					)
					(width 0)
					(fill yes)
				)
			)
		)
		(pad "2" smd custom
			(at 0 0.4572)
			(size 0.1524 0.1524)
			(layers "B.Cu" "B.Mask" "B.Paste")
			(net "GND")
			(options
				(clearance outline)
				(anchor circle)
			)
			(primitives
				(gr_poly
					(pts
						(arc
							(start -0.254 -0.3048)
							(mid -0.325842 -0.275042)
							(end -0.3556 -0.2032)
						)
						(arc
							(start -0.3556 0.2032)
							(mid -0.325842 0.275042)
							(end -0.254 0.3048)
						)
						(arc
							(start 0.254 0.3048)
							(mid 0.325842 0.275042)
							(end 0.3556 0.2032)
						)
						(arc
							(start 0.3556 -0.2032)
							(mid 0.325842 -0.275042)
							(end 0.254 -0.3048)
						)
					)
					(width 0)
					(fill yes)
				)
			)
		)
	)
	(footprint ""
		(layer "B.Cu")
		(at 192.73901 -33.573974 -90)
		(property "Reference" "R233"
			(at 0 0 90)
			(layer "B.SilkS")
			(hide yes)
			(effects
				(font
					(size 1.27 1.27)
				)
				(justify mirror)
			)
		)
		(property "Value" "4K7R2F-GP"
			(at -0.064008 -3.993896 270)
			(unlocked yes)
			(layer "B.Fab")
			(hide yes)
			(effects
				(font
					(size 1.016 1.016)
					(thickness 0.1524)
				)
				(justify mirror)
			)
		)
		(property "Device Type" "R402H16"
			(at -0.064008 -5.517896 270)
			(unlocked yes)
			(layer "B.Fab")
			(hide yes)
			(effects
				(font
					(size 1.016 1.016)
					(thickness 0.1524)
				)
				(justify mirror)
			)
		)
		(duplicate_pad_numbers_are_jumpers no)
		(fp_line
			(start -0.508 -0.9398)
			(end 0.508 -0.9398)
			(stroke
				(width 0.1524)
				(type default)
			)
			(layer "B.SilkS")
		)
		(fp_line
			(start 0.508 -0.9398)
			(end 0.508 0.9398)
			(stroke
				(width 0.1524)
				(type default)
			)
			(layer "B.SilkS")
		)
		(fp_rect
			(start 0.508 0.9398)
			(end -0.508 -0.9398)
			(stroke
				(width 0)
				(type default)
			)
			(fill no)
			(layer "B.CrtYd")
		)
		(fp_rect
			(start 0.508 0.9398)
			(end -0.508 -0.9398)
			(stroke
				(width 0)
				(type default)
			)
			(fill no)
			(layer "B.Fab")
		)
		(pad "1" smd custom
			(at 0 -0.4445 90)
			(size 0.1397 0.1397)
			(layers "B.Cu" "B.Mask" "B.Paste")
			(net "P1V8_C")
			(options
				(clearance outline)
				(anchor circle)
			)
			(primitives
				(gr_poly
					(pts
						(arc
							(start -0.1778 0.2794)
							(mid -0.249642 0.249642)
							(end -0.2794 0.1778)
						)
						(arc
							(start -0.2794 -0.1778)
							(mid -0.249642 -0.249642)
							(end -0.1778 -0.2794)
						)
						(arc
							(start 0.1778 -0.2794)
							(mid 0.249642 -0.249642)
							(end 0.2794 -0.1778)
						)
						(arc
							(start 0.2794 0.1778)
							(mid 0.249642 0.249642)
							(end 0.1778 0.2794)
						)
					)
					(width 0)
					(fill yes)
				)
			)
		)
		(pad "2" smd custom
			(at 0 0.4445 90)
			(size 0.1397 0.1397)
			(layers "B.Cu" "B.Mask" "B.Paste")
			(net "UART_SERCLK")
			(options
				(clearance outline)
				(anchor circle)
			)
			(primitives
				(gr_poly
					(pts
						(arc
							(start -0.1778 0.2794)
							(mid -0.249642 0.249642)
							(end -0.2794 0.1778)
						)
						(arc
							(start -0.2794 -0.1778)
							(mid -0.249642 -0.249642)
							(end -0.1778 -0.2794)
						)
						(arc
							(start 0.1778 -0.2794)
							(mid 0.249642 -0.249642)
							(end 0.2794 -0.1778)
						)
						(arc
							(start 0.2794 0.1778)
							(mid 0.249642 0.249642)
							(end 0.1778 0.2794)
						)
					)
					(width 0)
					(fill yes)
				)
			)
		)
	)
	(footprint ""
		(layer "B.Cu")
		(at 110.469172 -65.488058 -90)
		(property "Reference" "C161"
			(at 0 0 90)
			(layer "B.SilkS")
			(hide yes)
			(effects
				(font
					(size 1.27 1.27)
				)
				(justify mirror)
			)
		)
		(property "Value" "SCD1U6D3V1KX-GP"
			(at 2.8321 -1.7399 270)
			(unlocked yes)
			(layer "B.Fab")
			(hide yes)
			(effects
				(font
					(size 1.016 1.016)
					(thickness 0.1524)
				)
				(justify mirror)
			)
		)
		(property "Device Type" "C0201H13"
			(at 2.8321 -3.2639 270)
			(unlocked yes)
			(layer "B.Fab")
			(hide yes)
			(effects
				(font
					(size 1.016 1.016)
					(thickness 0.1524)
				)
				(justify mirror)
			)
		)
		(duplicate_pad_numbers_are_jumpers no)
		(fp_rect
			(start 0.2794 0.6477)
			(end -0.2794 -0.6477)
			(stroke
				(width 0)
				(type default)
			)
			(fill no)
			(layer "B.CrtYd")
		)
		(fp_rect
			(start 0.2794 0.6477)
			(end -0.2794 -0.6477)
			(stroke
				(width 0)
				(type default)
			)
			(fill no)
			(layer "B.Fab")
		)
		(pad "1" smd custom
			(at 0 -0.2794 90)
			(size 0.0762 0.0762)
			(layers "B.Cu" "B.Mask" "B.Paste")
			(net "P0V9")
			(options
				(clearance outline)
				(anchor circle)
			)
			(primitives
				(gr_poly
					(pts
						(arc
							(start 0.1524 0.127)
							(mid 0.137521 0.162921)
							(end 0.1016 0.1778)
						)
						(arc
							(start -0.1016 0.1778)
							(mid -0.137521 0.162921)
							(end -0.1524 0.127)
						)
						(arc
							(start -0.1524 -0.127)
							(mid -0.137521 -0.162921)
							(end -0.1016 -0.1778)
						)
						(arc
							(start 0.1016 -0.1778)
							(mid 0.137521 -0.162921)
							(end 0.1524 -0.127)
						)
					)
					(width 0)
					(fill yes)
				)
			)
		)
		(pad "2" smd custom
			(at 0 0.2794 90)
			(size 0.0762 0.0762)
			(layers "B.Cu" "B.Mask" "B.Paste")
			(net "GND")
			(options
				(clearance outline)
				(anchor circle)
			)
			(primitives
				(gr_poly
					(pts
						(arc
							(start 0.1524 0.127)
							(mid 0.137521 0.162921)
							(end 0.1016 0.1778)
						)
						(arc
							(start -0.1016 0.1778)
							(mid -0.137521 0.162921)
							(end -0.1524 0.127)
						)
						(arc
							(start -0.1524 -0.127)
							(mid -0.137521 -0.162921)
							(end -0.1016 -0.1778)
						)
						(arc
							(start 0.1016 -0.1778)
							(mid 0.137521 -0.162921)
							(end 0.1524 -0.127)
						)
					)
					(width 0)
					(fill yes)
				)
			)
		)
	)
	(footprint ""
		(layer "B.Cu")
		(at 184.8358 -29.972)
		(property "Reference" "TP144"
			(at 0 0 0)
			(layer "B.SilkS")
			(hide yes)
			(effects
				(font
					(size 1.27 1.27)
				)
				(justify mirror)
			)
		)
		(property "Value" "TPAD28-2-GP"
			(at 0.0127 -1.6637 0)
			(unlocked yes)
			(layer "B.Fab")
			(hide yes)
			(effects
				(font
					(size 1.016 1.016)
					(thickness 0.1524)
				)
				(justify mirror)
			)
		)
		(property "Device Type" "TPAD28"
			(at 0.0127 -3.1877 0)
			(unlocked yes)
			(layer "B.Fab")
			(hide yes)
			(effects
				(font
					(size 1.016 1.016)
					(thickness 0.1524)
				)
				(justify mirror)
			)
		)
		(duplicate_pad_numbers_are_jumpers no)
		(fp_poly
			(pts
				(arc
					(start 0.3556 0)
					(mid -0.3556 0)
					(end 0.3556 0)
				)
			)
			(stroke
				(width 0)
				(type default)
			)
			(fill no)
			(layer "B.CrtYd")
		)
		(fp_poly
			(pts
				(arc
					(start 0.6096 0)
					(mid -0.6096 0)
					(end 0.6096 0)
				)
			)
			(stroke
				(width 0)
				(type default)
			)
			(fill no)
			(layer "B.Fab")
		)
		(pad "1" smd circle
			(at 0 0 180)
			(size 0.7112 0.7112)
			(layers "B.Cu" "B.Mask" "B.Paste")
			(net "SPARE0")
		)
	)
	(footprint ""
		(layer "B.Cu")
		(at 70.485 -50.292 90)
		(property "Reference" "L9"
			(at 0 0 90)
			(layer "B.SilkS")
			(hide yes)
			(effects
				(font
					(size 1.27 1.27)
				)
				(justify mirror)
			)
		)
		(property "Value" "MPZ2012S300AT-GP"
			(at 0 -4.2418 90)
			(unlocked yes)
			(layer "B.Fab")
			(hide yes)
			(effects
				(font
					(size 1.016 1.016)
					(thickness 0.1524)
				)
				(justify mirror)
			)
		)
		(property "Device Type" "L805H42"
			(at 0 -5.7912 90)
			(unlocked yes)
			(layer "B.Fab")
			(hide yes)
			(effects
				(font
					(size 1.016 1.016)
					(thickness 0.1524)
				)
				(justify mirror)
			)
		)
		(duplicate_pad_numbers_are_jumpers no)
		(fp_line
			(start 0.889 -1.7018)
			(end -0.889 -1.7018)
			(stroke
				(width 0.1524)
				(type default)
			)
			(layer "B.SilkS")
		)
		(fp_line
			(start -0.889 -1.7018)
			(end -0.889 1.7018)
			(stroke
				(width 0.1524)
				(type default)
			)
			(layer "B.SilkS")
		)
		(fp_line
			(start 0.889 1.7018)
			(end 0.889 -1.7018)
			(stroke
				(width 0.1524)
				(type default)
			)
			(layer "B.SilkS")
		)
		(fp_line
			(start -0.889 1.7018)
			(end 0.889 1.7018)
			(stroke
				(width 0.1524)
				(type default)
			)
			(layer "B.SilkS")
		)
		(fp_rect
			(start 0.9652 1.778)
			(end -0.9652 -1.778)
			(stroke
				(width 0)
				(type default)
			)
			(fill no)
			(layer "B.CrtYd")
		)
		(fp_rect
			(start 0.9652 1.778)
			(end -0.9652 -1.778)
			(stroke
				(width 0)
				(type default)
			)
			(fill no)
			(layer "B.Fab")
		)
		(pad "1" smd rect
			(at 0 -0.9652 270)
			(size 1.397 1.143)
			(layers "B.Cu" "B.Mask" "B.Paste")
			(net "P0V9")
		)
		(pad "2" smd rect
			(at 0 0.9652 270)
			(size 1.397 1.143)
			(layers "B.Cu" "B.Mask" "B.Paste")
			(net "GB_VDDA")
		)
	)
)
